(kicad_pcb
	(version 20260206)
	(generator "pcbnew")
	(generator_version "10.0")
	(general
		(thickness 1.6)
		(legacy_teardrops no)
	)
	(paper "A4")
	(title_block
		(title "panther-plus-userver — 13130-1b_20150205.brd")
		(comment 1 "Honey Badger (Wiwynn) / footprints 146-153 of 1509")
	)
	(layers
		(0 "F.Cu" signal "TOP")
		(4 "In1.Cu" signal "L2")
		(6 "In2.Cu" signal "L3")
		(8 "In3.Cu" signal "L4")
		(10 "In4.Cu" signal "L5")
		(12 "In5.Cu" signal "L6")
		(14 "In6.Cu" signal "L7")
		(16 "In7.Cu" signal "L8")
		(18 "In8.Cu" signal "L9")
		(20 "In9.Cu" signal "L10")
		(22 "In10.Cu" signal "L11")
		(2 "B.Cu" signal "BOTTOM")
		(9 "F.Adhes" user "F.Adhesive")
		(11 "B.Adhes" user "B.Adhesive")
		(13 "F.Paste" user "Package Geometry/Pastemask Top")
		(15 "B.Paste" user "Package Geometry/Pastemask Bottom")
		(5 "F.SilkS" user "Ref Des/Silkscreen Top")
		(7 "B.SilkS" user "Ref Des/Silkscreen Bottom")
		(1 "F.Mask" user "Board Geometry/Soldermask Top")
		(3 "B.Mask" user "Board Geometry/Soldermask Bottom")
		(17 "Dwgs.User" user "User.Drawings")
		(19 "Cmts.User" user "User.Comments")
		(21 "Eco1.User" user "User.Eco1")
		(23 "Eco2.User" user "User.Eco2")
		(25 "Edge.Cuts" user "Board Geometry/Outline")
		(27 "Margin" user)
		(31 "F.CrtYd" user "Package Geometry/Place Bound Top")
		(29 "B.CrtYd" user "Package Geometry/Place Bound Bottom")
		(35 "F.Fab" user "Ref Des/Assembly Top")
		(33 "B.Fab" user "Ref Des/Assembly Bottom")
	)
	(footprint ""
		(layer "F.Cu")
		(at 49.4538 -12.7)
		(property "Reference" "C312"
			(at 0 0 0)
			(layer "F.SilkS")
			(hide yes)
			(effects
				(font
					(size 1.27 1.27)
				)
			)
		)
		(property "Value" "SCD047U25V2KX-GP"
			(at 1.8923 -1.2065 0)
			(unlocked yes)
			(layer "F.Fab")
			(hide yes)
			(effects
				(font
					(size 1.016 1.016)
					(thickness 0.1524)
				)
			)
		)
		(property "Device Type" "C402H22"
			(at 1.8923 -2.7305 0)
			(unlocked yes)
			(layer "F.Fab")
			(hide yes)
			(effects
				(font
					(size 1.016 1.016)
					(thickness 0.1524)
				)
			)
		)
		(duplicate_pad_numbers_are_jumpers no)
		(fp_rect
			(start -0.381 0.7366)
			(end 0.381 -0.7366)
			(stroke
				(width 0)
				(type default)
			)
			(fill no)
			(layer "F.CrtYd")
		)
		(fp_rect
			(start -0.381 0.7366)
			(end 0.381 -0.7366)
			(stroke
				(width 0)
				(type default)
			)
			(fill no)
			(layer "F.Fab")
		)
		(pad "1" smd custom
			(at 0 -0.4572)
			(size 0.1143 0.1143)
			(layers "F.Cu" "F.Mask" "F.Paste")
			(net "CPU_GBE_TX_DN0")
			(options
				(clearance outline)
				(anchor circle)
			)
			(primitives
				(gr_poly
					(pts
						(arc
							(start -0.254 -0.1778)
							(mid -0.239121 -0.213721)
							(end -0.2032 -0.2286)
						)
						(arc
							(start 0.2032 -0.2286)
							(mid 0.239121 -0.213721)
							(end 0.254 -0.1778)
						)
						(arc
							(start 0.254 0.1778)
							(mid 0.239121 0.213721)
							(end 0.2032 0.2286)
						)
						(arc
							(start -0.2032 0.2286)
							(mid -0.239121 0.213721)
							(end -0.254 0.1778)
						)
					)
					(width 0)
					(fill yes)
				)
			)
		)
		(pad "2" smd custom
			(at 0 0.4572)
			(size 0.1143 0.1143)
			(layers "F.Cu" "F.Mask" "F.Paste")
			(net "CPU_GBE_TX_C_DN0")
			(options
				(clearance outline)
				(anchor circle)
			)
			(primitives
				(gr_poly
					(pts
						(arc
							(start -0.254 -0.1778)
							(mid -0.239121 -0.213721)
							(end -0.2032 -0.2286)
						)
						(arc
							(start 0.2032 -0.2286)
							(mid 0.239121 -0.213721)
							(end 0.254 -0.1778)
						)
						(arc
							(start 0.254 0.1778)
							(mid 0.239121 0.213721)
							(end 0.2032 0.2286)
						)
						(arc
							(start -0.2032 0.2286)
							(mid -0.239121 0.213721)
							(end -0.254 0.1778)
						)
					)
					(width 0)
					(fill yes)
				)
			)
		)
	)
	(footprint ""
		(layer "F.Cu")
		(at 48.387 -16.0782 180)
		(property "Reference" "R348"
			(at 0 0 180)
			(layer "F.SilkS")
			(hide yes)
			(effects
				(font
					(size 1.27 1.27)
				)
			)
		)
		(property "Value" "4K7R2F-GP"
			(at 0.064008 -3.993896 180)
			(unlocked yes)
			(layer "F.Fab")
			(hide yes)
			(effects
				(font
					(size 1.016 1.016)
					(thickness 0.1524)
				)
			)
		)
		(property "Device Type" "R402H16"
			(at 0.064008 -5.517896 180)
			(unlocked yes)
			(layer "F.Fab")
			(hide yes)
			(effects
				(font
					(size 1.016 1.016)
					(thickness 0.1524)
				)
			)
		)
		(duplicate_pad_numbers_are_jumpers no)
		(fp_rect
			(start -0.381 0.8382)
			(end 0.381 -0.8382)
			(stroke
				(width 0)
				(type default)
			)
			(fill no)
			(layer "F.CrtYd")
		)
		(fp_rect
			(start -0.381 0.8382)
			(end 0.381 -0.8382)
			(stroke
				(width 0)
				(type default)
			)
			(fill no)
			(layer "F.Fab")
		)
		(pad "1" smd custom
			(at 0 -0.4318 180)
			(size 0.127 0.127)
			(layers "F.Cu" "F.Mask" "F.Paste")
			(net "P3V3")
			(options
				(clearance outline)
				(anchor circle)
			)
			(primitives
				(gr_poly
					(pts
						(arc
							(start -0.2032 -0.2794)
							(mid -0.239121 -0.264521)
							(end -0.254 -0.2286)
						)
						(arc
							(start -0.254 0.2286)
							(mid -0.239121 0.264521)
							(end -0.2032 0.2794)
						)
						(arc
							(start 0.2032 0.2794)
							(mid 0.239121 0.264521)
							(end 0.254 0.2286)
						)
						(arc
							(start 0.254 -0.2286)
							(mid 0.239121 -0.264521)
							(end 0.2032 -0.2794)
						)
					)
					(width 0)
					(fill yes)
				)
			)
		)
		(pad "2" smd custom
			(at 0 0.4318 180)
			(size 0.127 0.127)
			(layers "F.Cu" "F.Mask" "F.Paste")
			(net "CLKBUFF_OE3#")
			(options
				(clearance outline)
				(anchor circle)
			)
			(primitives
				(gr_poly
					(pts
						(arc
							(start -0.2032 -0.2794)
							(mid -0.239121 -0.264521)
							(end -0.254 -0.2286)
						)
						(arc
							(start -0.254 0.2286)
							(mid -0.239121 0.264521)
							(end -0.2032 0.2794)
						)
						(arc
							(start 0.2032 0.2794)
							(mid 0.239121 0.264521)
							(end 0.254 0.2286)
						)
						(arc
							(start 0.254 -0.2286)
							(mid 0.239121 -0.264521)
							(end 0.2032 -0.2794)
						)
					)
					(width 0)
					(fill yes)
				)
			)
		)
	)
	(footprint ""
		(layer "F.Cu")
		(at 44.704 -21.463 -90)
		(property "Reference" "R246"
			(at 0 0 270)
			(layer "F.SilkS")
			(hide yes)
			(effects
				(font
					(size 1.27 1.27)
				)
			)
		)
		(property "Value" "1KR2F-3-GP"
			(at 0.064008 -3.993896 270)
			(unlocked yes)
			(layer "F.Fab")
			(hide yes)
			(effects
				(font
					(size 1.016 1.016)
					(thickness 0.1524)
				)
			)
		)
		(property "Device Type" "R402H16"
			(at 0.064008 -5.517896 270)
			(unlocked yes)
			(layer "F.Fab")
			(hide yes)
			(effects
				(font
					(size 1.016 1.016)
					(thickness 0.1524)
				)
			)
		)
		(duplicate_pad_numbers_are_jumpers no)
		(fp_rect
			(start -0.381 0.8382)
			(end 0.381 -0.8382)
			(stroke
				(width 0)
				(type default)
			)
			(fill no)
			(layer "F.CrtYd")
		)
		(fp_rect
			(start -0.381 0.8382)
			(end 0.381 -0.8382)
			(stroke
				(width 0)
				(type default)
			)
			(fill no)
			(layer "F.Fab")
		)
		(pad "1" smd custom
			(at 0 -0.4318 270)
			(size 0.127 0.127)
			(layers "F.Cu" "F.Mask" "F.Paste")
			(net "P1V0")
			(options
				(clearance outline)
				(anchor circle)
			)
			(primitives
				(gr_poly
					(pts
						(arc
							(start -0.2032 -0.2794)
							(mid -0.239121 -0.264521)
							(end -0.254 -0.2286)
						)
						(arc
							(start -0.254 0.2286)
							(mid -0.239121 0.264521)
							(end -0.2032 0.2794)
						)
						(arc
							(start 0.2032 0.2794)
							(mid 0.239121 0.264521)
							(end 0.254 0.2286)
						)
						(arc
							(start 0.254 -0.2286)
							(mid 0.239121 -0.264521)
							(end 0.2032 -0.2794)
						)
					)
					(width 0)
					(fill yes)
				)
			)
		)
		(pad "2" smd custom
			(at 0 0.4318 270)
			(size 0.127 0.127)
			(layers "F.Cu" "F.Mask" "F.Paste")
			(net "XDP_CPU_PRDY#")
			(options
				(clearance outline)
				(anchor circle)
			)
			(primitives
				(gr_poly
					(pts
						(arc
							(start -0.2032 -0.2794)
							(mid -0.239121 -0.264521)
							(end -0.254 -0.2286)
						)
						(arc
							(start -0.254 0.2286)
							(mid -0.239121 0.264521)
							(end -0.2032 0.2794)
						)
						(arc
							(start 0.2032 0.2794)
							(mid 0.239121 0.264521)
							(end 0.254 0.2286)
						)
						(arc
							(start 0.254 -0.2286)
							(mid 0.239121 -0.264521)
							(end 0.2032 -0.2794)
						)
					)
					(width 0)
					(fill yes)
				)
			)
		)
	)
	(footprint ""
		(layer "F.Cu")
		(at 5.715 -37.211 -90)
		(property "Reference" "PC187"
			(at 0 0 270)
			(layer "F.SilkS")
			(hide yes)
			(effects
				(font
					(size 1.27 1.27)
				)
			)
		)
		(property "Value" "SC22U25V5MX-GP"
			(at 0 -4.9022 270)
			(unlocked yes)
			(layer "F.Fab")
			(hide yes)
			(effects
				(font
					(size 1.016 1.016)
					(thickness 0.1524)
				)
			)
		)
		(property "Device Type" "C805H58"
			(at 0 -6.8072 270)
			(unlocked yes)
			(layer "F.Fab")
			(hide yes)
			(effects
				(font
					(size 1.016 1.016)
					(thickness 0.1524)
				)
			)
		)
		(duplicate_pad_numbers_are_jumpers no)
		(fp_line
			(start 0.6096 0)
			(end -0.6096 0)
			(stroke
				(width 0.3048)
				(type default)
			)
			(layer "F.SilkS")
		)
		(fp_poly
			(pts
				(xy -0.9017 1.4351) (xy 0.9017 1.4351) (xy 0.9017 -1.4351) (xy -0.9017 -1.4351)
			)
			(stroke
				(width 0)
				(type default)
			)
			(fill no)
			(layer "F.CrtYd")
		)
		(fp_poly
			(pts
				(xy 0.9017 1.4351) (xy 0.9017 -1.4351) (xy -0.9017 -1.4351) (xy -0.9017 1.4351)
			)
			(stroke
				(width 0)
				(type default)
			)
			(fill no)
			(layer "F.Fab")
		)
		(pad "1" smd rect
			(at 0 -0.8382 270)
			(size 1.5494 0.9398)
			(layers "F.Cu" "F.Mask" "F.Paste")
			(net "P3V3_STBY_VIN")
		)
		(pad "2" smd rect
			(at 0 0.8382 270)
			(size 1.5494 0.9398)
			(layers "F.Cu" "F.Mask" "F.Paste")
			(net "GND")
		)
	)
	(footprint ""
		(layer "F.Cu")
		(at 187.071 -27.0002)
		(property "Reference" "PR160"
			(at 0 0 0)
			(layer "F.SilkS")
			(hide yes)
			(effects
				(font
					(size 1.27 1.27)
				)
			)
		)
		(property "Value" "0R2J-2-GP"
			(at 1.7907 -1.1176 0)
			(unlocked yes)
			(layer "F.Fab")
			(hide yes)
			(effects
				(font
					(size 1.016 1.016)
					(thickness 0.1524)
				)
			)
		)
		(property "Device Type" "R402H16"
			(at 1.7907 -2.6416 0)
			(unlocked yes)
			(layer "F.Fab")
			(hide yes)
			(effects
				(font
					(size 1.016 1.016)
					(thickness 0.1524)
				)
			)
		)
		(duplicate_pad_numbers_are_jumpers no)
		(fp_rect
			(start -0.381 0.8382)
			(end 0.381 -0.8382)
			(stroke
				(width 0)
				(type default)
			)
			(fill no)
			(layer "F.CrtYd")
		)
		(fp_rect
			(start -0.381 0.8382)
			(end 0.381 -0.8382)
			(stroke
				(width 0)
				(type default)
			)
			(fill no)
			(layer "F.Fab")
		)
		(pad "1" smd custom
			(at 0 -0.4318)
			(size 0.127 0.127)
			(layers "F.Cu" "F.Mask" "F.Paste")
			(net "VR_PVDDR_A_VSEN")
			(options
				(clearance outline)
				(anchor circle)
			)
			(primitives
				(gr_poly
					(pts
						(arc
							(start -0.2032 -0.2794)
							(mid -0.239121 -0.264521)
							(end -0.254 -0.2286)
						)
						(arc
							(start -0.254 0.2286)
							(mid -0.239121 0.264521)
							(end -0.2032 0.2794)
						)
						(arc
							(start 0.2032 0.2794)
							(mid 0.239121 0.264521)
							(end 0.254 0.2286)
						)
						(arc
							(start 0.254 -0.2286)
							(mid 0.239121 -0.264521)
							(end 0.2032 -0.2794)
						)
					)
					(width 0)
					(fill yes)
				)
			)
		)
		(pad "2" smd custom
			(at 0 0.4318)
			(size 0.127 0.127)
			(layers "F.Cu" "F.Mask" "F.Paste")
			(net "VSENSE_PVDDR_A_VSEN")
			(options
				(clearance outline)
				(anchor circle)
			)
			(primitives
				(gr_poly
					(pts
						(arc
							(start -0.2032 -0.2794)
							(mid -0.239121 -0.264521)
							(end -0.254 -0.2286)
						)
						(arc
							(start -0.254 0.2286)
							(mid -0.239121 0.264521)
							(end -0.2032 0.2794)
						)
						(arc
							(start 0.2032 0.2794)
							(mid 0.239121 0.264521)
							(end 0.254 0.2286)
						)
						(arc
							(start 0.254 -0.2286)
							(mid 0.239121 -0.264521)
							(end 0.2032 -0.2794)
						)
					)
					(width 0)
					(fill yes)
				)
			)
		)
	)
	(footprint ""
		(layer "F.Cu")
		(at 38.9128 -54.483)
		(property "Reference" "PC32"
			(at 0 0 0)
			(layer "F.SilkS")
			(hide yes)
			(effects
				(font
					(size 1.27 1.27)
				)
			)
		)
		(property "Value" "SCD1U25V2KX-2-GP"
			(at 1.8923 -1.2065 0)
			(unlocked yes)
			(layer "F.Fab")
			(hide yes)
			(effects
				(font
					(size 1.016 1.016)
					(thickness 0.1524)
				)
			)
		)
		(property "Device Type" "C402H22"
			(at 1.8923 -2.7305 0)
			(unlocked yes)
			(layer "F.Fab")
			(hide yes)
			(effects
				(font
					(size 1.016 1.016)
					(thickness 0.1524)
				)
			)
		)
		(duplicate_pad_numbers_are_jumpers no)
		(fp_rect
			(start -0.381 0.7366)
			(end 0.381 -0.7366)
			(stroke
				(width 0)
				(type default)
			)
			(fill no)
			(layer "F.CrtYd")
		)
		(fp_rect
			(start -0.381 0.7366)
			(end 0.381 -0.7366)
			(stroke
				(width 0)
				(type default)
			)
			(fill no)
			(layer "F.Fab")
		)
		(pad "1" smd custom
			(at 0 -0.4572)
			(size 0.1143 0.1143)
			(layers "F.Cu" "F.Mask" "F.Paste")
			(net "VR_FET_SW_P12V_PVCCP_PVNN")
			(options
				(clearance outline)
				(anchor circle)
			)
			(primitives
				(gr_poly
					(pts
						(arc
							(start -0.254 -0.1778)
							(mid -0.239121 -0.213721)
							(end -0.2032 -0.2286)
						)
						(arc
							(start 0.2032 -0.2286)
							(mid 0.239121 -0.213721)
							(end 0.254 -0.1778)
						)
						(arc
							(start 0.254 0.1778)
							(mid 0.239121 0.213721)
							(end 0.2032 0.2286)
						)
						(arc
							(start -0.2032 0.2286)
							(mid -0.239121 0.213721)
							(end -0.254 0.1778)
						)
					)
					(width 0)
					(fill yes)
				)
			)
		)
		(pad "2" smd custom
			(at 0 0.4572)
			(size 0.1143 0.1143)
			(layers "F.Cu" "F.Mask" "F.Paste")
			(net "GND")
			(options
				(clearance outline)
				(anchor circle)
			)
			(primitives
				(gr_poly
					(pts
						(arc
							(start -0.254 -0.1778)
							(mid -0.239121 -0.213721)
							(end -0.2032 -0.2286)
						)
						(arc
							(start 0.2032 -0.2286)
							(mid 0.239121 -0.213721)
							(end 0.254 -0.1778)
						)
						(arc
							(start 0.254 0.1778)
							(mid 0.239121 0.213721)
							(end 0.2032 0.2286)
						)
						(arc
							(start -0.2032 0.2286)
							(mid -0.239121 0.213721)
							(end -0.254 0.1778)
						)
					)
					(width 0)
					(fill yes)
				)
			)
		)
	)
	(footprint ""
		(layer "F.Cu")
		(at 112.522 -71.12)
		(property "Reference" "R235"
			(at 0 0 0)
			(layer "F.SilkS")
			(hide yes)
			(effects
				(font
					(size 1.27 1.27)
				)
			)
		)
		(property "Value" "4K7R2F-GP"
			(at 0.064008 -3.993896 0)
			(unlocked yes)
			(layer "F.Fab")
			(hide yes)
			(effects
				(font
					(size 1.016 1.016)
					(thickness 0.1524)
				)
			)
		)
		(property "Device Type" "R402H16"
			(at 0.064008 -5.517896 0)
			(unlocked yes)
			(layer "F.Fab")
			(hide yes)
			(effects
				(font
					(size 1.016 1.016)
					(thickness 0.1524)
				)
			)
		)
		(duplicate_pad_numbers_are_jumpers no)
		(fp_rect
			(start -0.381 0.8382)
			(end 0.381 -0.8382)
			(stroke
				(width 0)
				(type default)
			)
			(fill no)
			(layer "F.CrtYd")
		)
		(fp_rect
			(start -0.381 0.8382)
			(end 0.381 -0.8382)
			(stroke
				(width 0)
				(type default)
			)
			(fill no)
			(layer "F.Fab")
		)
		(pad "1" smd custom
			(at 0 -0.4318)
			(size 0.127 0.127)
			(layers "F.Cu" "F.Mask" "F.Paste")
			(net "CHA_1_SA0")
			(options
				(clearance outline)
				(anchor circle)
			)
			(primitives
				(gr_poly
					(pts
						(arc
							(start -0.2032 -0.2794)
							(mid -0.239121 -0.264521)
							(end -0.254 -0.2286)
						)
						(arc
							(start -0.254 0.2286)
							(mid -0.239121 0.264521)
							(end -0.2032 0.2794)
						)
						(arc
							(start 0.2032 0.2794)
							(mid 0.239121 0.264521)
							(end 0.254 0.2286)
						)
						(arc
							(start 0.254 -0.2286)
							(mid 0.239121 -0.264521)
							(end 0.2032 -0.2794)
						)
					)
					(width 0)
					(fill yes)
				)
			)
		)
		(pad "2" smd custom
			(at 0 0.4318)
			(size 0.127 0.127)
			(layers "F.Cu" "F.Mask" "F.Paste")
			(net "GND")
			(options
				(clearance outline)
				(anchor circle)
			)
			(primitives
				(gr_poly
					(pts
						(arc
							(start -0.2032 -0.2794)
							(mid -0.239121 -0.264521)
							(end -0.254 -0.2286)
						)
						(arc
							(start -0.254 0.2286)
							(mid -0.239121 0.264521)
							(end -0.2032 0.2794)
						)
						(arc
							(start 0.2032 0.2794)
							(mid 0.239121 0.264521)
							(end 0.254 0.2286)
						)
						(arc
							(start 0.254 -0.2286)
							(mid 0.239121 -0.264521)
							(end 0.2032 -0.2794)
						)
					)
					(width 0)
					(fill yes)
				)
			)
		)
	)
	(footprint ""
		(layer "F.Cu")
		(at 164.846 -43.942 -90)
		(property "Reference" "R86"
			(at 0 0 270)
			(layer "F.SilkS")
			(hide yes)
			(effects
				(font
					(size 1.27 1.27)
				)
			)
		)
		(property "Value" "33R2F-3-GP"
			(at 0.064008 -3.993896 270)
			(unlocked yes)
			(layer "F.Fab")
			(hide yes)
			(effects
				(font
					(size 1.016 1.016)
					(thickness 0.1524)
				)
			)
		)
		(property "Device Type" "R402H16"
			(at 0.064008 -5.517896 270)
			(unlocked yes)
			(layer "F.Fab")
			(hide yes)
			(effects
				(font
					(size 1.016 1.016)
					(thickness 0.1524)
				)
			)
		)
		(duplicate_pad_numbers_are_jumpers no)
		(fp_rect
			(start -0.381 0.8382)
			(end 0.381 -0.8382)
			(stroke
				(width 0)
				(type default)
			)
			(fill no)
			(layer "F.CrtYd")
		)
		(fp_rect
			(start -0.381 0.8382)
			(end 0.381 -0.8382)
			(stroke
				(width 0)
				(type default)
			)
			(fill no)
			(layer "F.Fab")
		)
		(pad "1" smd custom
			(at 0 -0.4318 270)
			(size 0.127 0.127)
			(layers "F.Cu" "F.Mask" "F.Paste")
			(net "OSC_5M_CLK_R")
			(options
				(clearance outline)
				(anchor circle)
			)
			(primitives
				(gr_poly
					(pts
						(arc
							(start -0.2032 -0.2794)
							(mid -0.239121 -0.264521)
							(end -0.254 -0.2286)
						)
						(arc
							(start -0.254 0.2286)
							(mid -0.239121 0.264521)
							(end -0.2032 0.2794)
						)
						(arc
							(start 0.2032 0.2794)
							(mid 0.239121 0.264521)
							(end 0.254 0.2286)
						)
						(arc
							(start 0.254 -0.2286)
							(mid 0.239121 -0.264521)
							(end 0.2032 -0.2794)
						)
					)
					(width 0)
					(fill yes)
				)
			)
		)
		(pad "2" smd custom
			(at 0 0.4318 270)
			(size 0.127 0.127)
			(layers "F.Cu" "F.Mask" "F.Paste")
			(net "FPGA_CLK_DP")
			(options
				(clearance outline)
				(anchor circle)
			)
			(primitives
				(gr_poly
					(pts
						(arc
							(start -0.2032 -0.2794)
							(mid -0.239121 -0.264521)
							(end -0.254 -0.2286)
						)
						(arc
							(start -0.254 0.2286)
							(mid -0.239121 0.264521)
							(end -0.2032 0.2794)
						)
						(arc
							(start 0.2032 0.2794)
							(mid 0.239121 0.264521)
							(end 0.254 0.2286)
						)
						(arc
							(start 0.254 -0.2286)
							(mid 0.239121 -0.264521)
							(end 0.2032 -0.2794)
						)
					)
					(width 0)
					(fill yes)
				)
			)
		)
	)
)
